#ISCELL
  mstr_misc dns *
  *
#ISCELL
  pure_quanta quanta_title_block_c *
  *
#ISCELL
  logical_power universal_gnd *
  page187_i11
#ISCELL
  logical_power universal_power *
  page187_i12
#CELL
  pure_quanta q_res *
  page187_i13
#CELL
  pure_quanta q_res *
  page187_i14
#ISCELL
  logical_power universal_gnd *
  page187_i15
#ISCELL
  standard offpage *
  page187_i16
#ISCELL
  logical_power universal_power *
  page187_i17
#CELL
  pure_quanta q_res *
  page187_i18
#ISCELL
  standard offpage *
  page187_i19
#ISCELL
  logical_power universal_power *
  page187_i20
#CELL
  pure_quanta q_res *
  page187_i21
#ISCELL
  standard offpage *
  page187_i22
#CELL
  pure_quanta q_res *
  page187_i23
#ISCELL
  logical_power universal_gnd *
  page187_i24
#ISCELL
  logical_power universal_power *
  page187_i25
#ISCELL
  standard offpage *
  page187_i27
#ISCELL
  logical_power universal_power *
  page187_i30
#ISCELL
  standard offpage *
  page187_i32
#ISCELL
  standard offpage *
  page187_i33
#ISCELL
  logical_power universal_gnd *
  page187_i35
#CELL
  pure_quanta q_res *
  page187_i36
#ISCELL
  logical_power universal_gnd *
  page187_i37
#ISCELL
  logical_power universal_power *
  page187_i38
#CELL
  pure_quanta q_res *
  page187_i39
#ISCELL
  standard offpage *
  page187_i4
#CELL
  pure_quanta q_res *
  page187_i40
#ISCELL
  logical_power universal_gnd *
  page187_i41
#ISCELL
  logical_power universal_power *
  page187_i42
#CELL
  pure_quanta q_res *
  page187_i43
#CELL
  pure_quanta q_res *
  page187_i44
#ISCELL
  logical_power universal_gnd *
  page187_i45
#ISCELL
  standard offpage *
  page187_i46
#ISCELL
  logical_power universal_power *
  page187_i47
#CELL
  pure_quanta q_res *
  page187_i48
#ISCELL
  standard offpage *
  page187_i5
#CELL
  pure_quanta q_res *
  page187_i51
#CELL
  pure_quanta q_res *
  page187_i53
#CELL
  pure_quanta q_res *
  page187_i54
#CELL
  pure_quanta q_res *
  page187_i55
#CELL
  pure_quanta q_res *
  page187_i56
#ISCELL
  logical_power universal_power *
  page187_i8
